# BASEBOARD_FAB2 (Tioga Pass) — schematic netlist excerpt (pin names and nets, part order shuffled) for the footprints in the layout excerpt that follows; sources: Cadence DE-HDL packaged netlist, KiCad conversion of Wiwynn_Tioga_Pass_MB.brd

R2P16  RES  10.0K 1% CHIP  pkg 0402  page 185 : A = P3V3_STBY ; B = FM_M2_DET_LVC3
R1D14  RES  105.0K 1% CHIP  pkg 0402  page 200 : A = A_HSC_CSOUT ; B = A_HSC_LOW
R12W16  665KR5B-1-GP  0.1%  pkg SMD-RG3  page 197 : \1\ = P12V_STBY ; \2\ = VR_PVDDQ_KLM_AIINSEN

(kicad_pcb
	(version 20260206)
	(generator "pcbnew")
	(generator_version "10.0")
	(general
		(thickness 1.6)
		(legacy_teardrops no)
	)
	(paper "A4")
	(title_block
		(title "Wiwynn_Tioga_Pass_MB.brd")
		(comment 1 "Tioga Pass / footprints 565-567 of 4770")
	)
	(layers
		(0 "F.Cu" signal "TOP")
		(4 "In1.Cu" signal "L2GND")
		(6 "In2.Cu" signal "L3")
		(8 "In3.Cu" signal "L4GND")
		(10 "In4.Cu" signal "L5")
		(12 "In5.Cu" signal "L6GND")
		(14 "In6.Cu" signal "L7VCC")
		(16 "In7.Cu" signal "L8VCC")
		(18 "In8.Cu" signal "L9GND")
		(20 "In9.Cu" signal "L10")
		(22 "In10.Cu" signal "L11GND")
		(24 "In11.Cu" signal "L12")
		(26 "In12.Cu" signal "L13GND")
		(2 "B.Cu" signal "BOTTOM")
		(9 "F.Adhes" user "F.Adhesive")
		(11 "B.Adhes" user "B.Adhesive")
		(13 "F.Paste" user "Package Geometry/Pastemask Top")
		(15 "B.Paste" user "Package Geometry/Pastemask Bottom")
		(5 "F.SilkS" user "Ref Des/Silkscreen Top")
		(7 "B.SilkS" user "Ref Des/Silkscreen Bottom")
		(1 "F.Mask" user "Board Geometry/Soldermask Top")
		(3 "B.Mask" user "Board Geometry/Soldermask Bottom")
		(17 "Dwgs.User" user "User.Drawings")
		(19 "Cmts.User" user "User.Comments")
		(21 "Eco1.User" user "User.Eco1")
		(23 "Eco2.User" user "User.Eco2")
		(25 "Edge.Cuts" user "Board Geometry/Outline")
		(27 "Margin" user)
		(31 "F.CrtYd" user "Package Geometry/Place Bound Top")
		(29 "B.CrtYd" user "Package Geometry/Place Bound Bottom")
		(35 "F.Fab" user "Ref Des/Assembly Top")
		(33 "B.Fab" user "Ref Des/Assembly Bottom")
	)
	(footprint ""
		(layer "F.Cu")
		(at 22.66188 -83.24342 180)
		(property "Reference" "R1D14"
			(at 0 0 180)
			(layer "F.SilkS")
			(hide yes)
			(effects
				(font
					(size 1.27 1.27)
				)
			)
		)
		(property "Value" ""
			(at 0 0 180)
			(layer "F.Fab")
			(effects
				(font
					(size 1.27 1.27)
				)
			)
		)
		(duplicate_pad_numbers_are_jumpers no)
		(fp_poly
			(pts
				(xy -0.2794 -0.1016) (xy 0.2794 -0.1016) (xy 0.2794 0.9906) (xy -0.2794 0.9906)
			)
			(stroke
				(width 0)
				(type default)
			)
			(fill no)
			(layer "F.CrtYd")
		)
		(fp_line
			(start 0.2794 0.9906)
			(end 0.2794 -0.1016)
			(stroke
				(width 0.1)
				(type default)
			)
			(layer "F.Fab")
		)
		(fp_line
			(start 0.2794 -0.1016)
			(end -0.2794 -0.1016)
			(stroke
				(width 0.1)
				(type default)
			)
			(layer "F.Fab")
		)
		(fp_line
			(start -0.2794 0.9906)
			(end 0.2794 0.9906)
			(stroke
				(width 0.1)
				(type default)
			)
			(layer "F.Fab")
		)
		(fp_line
			(start -0.2794 -0.1016)
			(end -0.2794 0.9906)
			(stroke
				(width 0.1)
				(type default)
			)
			(layer "F.Fab")
		)
		(pad "1" smd rect
			(at 0 0 180)
			(size 0.508 0.508)
			(layers "F.Cu" "F.Mask" "F.Paste")
			(net "A_HSC_CSOUT")
		)
		(pad "2" smd rect
			(at 0 0.889 180)
			(size 0.508 0.508)
			(layers "F.Cu" "F.Mask" "F.Paste")
			(net "A_HSC_LOW")
		)
		(zone
			(layer "F.Cu")
			(hatch none 0.5)
			(connect_pads
				(clearance 0)
			)
			(min_thickness 0.25)
			(keepout
				(tracks not_allowed)
				(vias allowed)
				(pads allowed)
				(copperpour not_allowed)
				(footprints allowed)
			)
			(placement
				(enabled no)
				(sheetname "")
			)
			(fill
				(thermal_gap 0.5)
				(thermal_bridge_width 0.5)
				(island_removal_mode 0)
			)
			(polygon
				(pts
					(xy 22.91588 -83.87842) (xy 22.40788 -83.87842) (xy 22.40788 -83.49742) (xy 22.91588 -83.49742)
				)
			)
		)
		(zone
			(layer "F.Cu")
			(hatch none 0.5)
			(connect_pads
				(clearance 0)
			)
			(min_thickness 0.25)
			(keepout
				(tracks allowed)
				(vias not_allowed)
				(pads allowed)
				(copperpour not_allowed)
				(footprints allowed)
			)
			(placement
				(enabled no)
				(sheetname "")
			)
			(fill
				(thermal_gap 0.5)
				(thermal_bridge_width 0.5)
				(island_removal_mode 0)
			)
			(polygon
				(pts
					(xy 22.91588 -83.49742) (xy 22.40788 -83.49742) (xy 22.40788 -83.87842) (xy 22.91588 -83.87842)
				)
			)
		)
	)
	(footprint ""
		(layer "F.Cu")
		(at 10.180828 -126.827026 -90)
		(property "Reference" "R12W16"
			(at 0 0 270)
			(layer "F.SilkS")
			(hide yes)
			(effects
				(font
					(size 1.27 1.27)
				)
			)
		)
		(property "Value" "*"
			(at 0 -8.9535 270)
			(unlocked yes)
			(layer "F.Fab")
			(hide yes)
			(effects
				(font
					(size 1.27 1.016)
					(thickness 0.1524)
				)
			)
		)
		(property "Device Type" "665KR5B-1-GP_SMD-RG3-665KR5B-1A"
			(at 0 -10.6299 270)
			(unlocked yes)
			(layer "F.Fab")
			(hide yes)
			(effects
				(font
					(size 1.27 1.016)
					(thickness 0.1524)
				)
			)
		)
		(duplicate_pad_numbers_are_jumpers no)
		(fp_line
			(start -0.889 1.7018)
			(end 0.889 1.7018)
			(stroke
				(width 0.1524)
				(type default)
			)
			(layer "F.SilkS")
		)
		(fp_line
			(start 0.889 1.7018)
			(end 0.889 -0.508)
			(stroke
				(width 0.1524)
				(type default)
			)
			(layer "F.SilkS")
		)
		(fp_line
			(start -0.889 0.0762)
			(end -0.889 1.7018)
			(stroke
				(width 0.1524)
				(type default)
			)
			(layer "F.SilkS")
		)
		(fp_line
			(start -0.889 -1.7018)
			(end -0.889 0.2794)
			(stroke
				(width 0.1524)
				(type default)
			)
			(layer "F.SilkS")
		)
		(fp_line
			(start 0.889 -1.7018)
			(end 0.889 -0.381)
			(stroke
				(width 0.1524)
				(type default)
			)
			(layer "F.SilkS")
		)
		(fp_line
			(start 0.889 -1.7018)
			(end -0.889 -1.7018)
			(stroke
				(width 0.1524)
				(type default)
			)
			(layer "F.SilkS")
		)
		(fp_poly
			(pts
				(xy 0.9652 -1.778) (xy 0.9652 1.778) (xy -0.9652 1.778) (xy -0.9652 -1.778)
			)
			(stroke
				(width 0)
				(type default)
			)
			(fill no)
			(layer "F.CrtYd")
		)
		(fp_rect
			(start -0.9652 1.778)
			(end 0.9652 -1.778)
			(stroke
				(width 0)
				(type default)
			)
			(fill no)
			(layer "F.Fab")
		)
		(pad "1" smd rect
			(at 0 -0.9652 270)
			(size 1.397 1.143)
			(layers "F.Cu" "F.Mask" "F.Paste")
			(net "P12V_STBY")
		)
		(pad "2" smd rect
			(at 0 0.9652 270)
			(size 1.397 1.143)
			(layers "F.Cu" "F.Mask" "F.Paste")
			(net "VR_PVDDQ_KLM_AIINSEN")
		)
	)
	(footprint ""
		(layer "F.Cu")
		(at 400.685 -82.3595 180)
		(property "Reference" "R2P16"
			(at 0 0 180)
			(layer "F.SilkS")
			(hide yes)
			(effects
				(font
					(size 1.27 1.27)
				)
			)
		)
		(property "Value" ""
			(at 0 0 180)
			(layer "F.Fab")
			(effects
				(font
					(size 1.27 1.27)
				)
			)
		)
		(duplicate_pad_numbers_are_jumpers no)
		(fp_poly
			(pts
				(xy -0.2794 -0.1016) (xy 0.2794 -0.1016) (xy 0.2794 0.9906) (xy -0.2794 0.9906)
			)
			(stroke
				(width 0)
				(type default)
			)
			(fill no)
			(layer "F.CrtYd")
		)
		(fp_line
			(start 0.2794 0.9906)
			(end 0.2794 -0.1016)
			(stroke
				(width 0.1)
				(type default)
			)
			(layer "F.Fab")
		)
		(fp_line
			(start 0.2794 -0.1016)
			(end -0.2794 -0.1016)
			(stroke
				(width 0.1)
				(type default)
			)
			(layer "F.Fab")
		)
		(fp_line
			(start -0.2794 0.9906)
			(end 0.2794 0.9906)
			(stroke
				(width 0.1)
				(type default)
			)
			(layer "F.Fab")
		)
		(fp_line
			(start -0.2794 -0.1016)
			(end -0.2794 0.9906)
			(stroke
				(width 0.1)
				(type default)
			)
			(layer "F.Fab")
		)
		(pad "1" smd rect
			(at 0 0 180)
			(size 0.508 0.508)
			(layers "F.Cu" "F.Mask" "F.Paste")
			(net "P3V3_STBY")
		)
		(pad "2" smd rect
			(at 0 0.889 180)
			(size 0.508 0.508)
			(layers "F.Cu" "F.Mask" "F.Paste")
			(net "FM_M2_DET_LVC3")
		)
		(zone
			(layer "F.Cu")
			(hatch none 0.5)
			(connect_pads
				(clearance 0)
			)
			(min_thickness 0.25)
			(keepout
				(tracks not_allowed)
				(vias allowed)
				(pads allowed)
				(copperpour not_allowed)
				(footprints allowed)
			)
			(placement
				(enabled no)
				(sheetname "")
			)
			(fill
				(thermal_gap 0.5)
				(thermal_bridge_width 0.5)
				(island_removal_mode 0)
			)
			(polygon
				(pts
					(xy 400.939 -82.9945) (xy 400.431 -82.9945) (xy 400.431 -82.6135) (xy 400.939 -82.6135)
				)
			)
		)
		(zone
			(layer "F.Cu")
			(hatch none 0.5)
			(connect_pads
				(clearance 0)
			)
			(min_thickness 0.25)
			(keepout
				(tracks allowed)
				(vias not_allowed)
				(pads allowed)
				(copperpour not_allowed)
				(footprints allowed)
			)
			(placement
				(enabled no)
				(sheetname "")
			)
			(fill
				(thermal_gap 0.5)
				(thermal_bridge_width 0.5)
				(island_removal_mode 0)
			)
			(polygon
				(pts
					(xy 400.939 -82.6135) (xy 400.431 -82.6135) (xy 400.431 -82.9945) (xy 400.939 -82.9945)
				)
			)
		)
	)
)
